(kicad_pcb
	(version 20260206)
	(generator "pcbnew")
	(generator_version "10.0")
	(general
		(thickness 1.6)
		(legacy_teardrops no)
	)
	(paper "A4")
	(title_block
		(title "9052_F0T_PDB_Converter_Brick_F_V03_1208_1600_OCP.brd")
		(comment 1 "Grand Teton / footprints 62-69 of 578")
	)
	(layers
		(0 "F.Cu" signal "TOP")
		(4 "In1.Cu" signal "GND")
		(6 "In2.Cu" signal "IN1")
		(8 "In3.Cu" signal "GND1")
		(10 "In4.Cu" signal "VCC")
		(12 "In5.Cu" signal "VCC1")
		(14 "In6.Cu" signal "GND2")
		(16 "In7.Cu" signal "IN2")
		(18 "In8.Cu" signal "GND3")
		(2 "B.Cu" signal "BOTTOM")
		(9 "F.Adhes" user "F.Adhesive")
		(11 "B.Adhes" user "B.Adhesive")
		(13 "F.Paste" user "Package Geometry/Pastemask Top")
		(15 "B.Paste" user "Package Geometry/Pastemask Bottom")
		(5 "F.SilkS" user "Ref Des/Silkscreen Top")
		(7 "B.SilkS" user "Ref Des/Silkscreen Bottom")
		(1 "F.Mask" user "Board Geometry/Soldermask Top")
		(3 "B.Mask" user "Board Geometry/Soldermask Bottom")
		(17 "Dwgs.User" user "User.Drawings")
		(19 "Cmts.User" user "User.Comments")
		(21 "Eco1.User" user "User.Eco1")
		(23 "Eco2.User" user "User.Eco2")
		(25 "Edge.Cuts" user "Board Geometry/Outline")
		(27 "Margin" user)
		(31 "F.CrtYd" user "Package Geometry/Place Bound Top")
		(29 "B.CrtYd" user "Package Geometry/Place Bound Bottom")
		(35 "F.Fab" user "Ref Des/Assembly Top")
		(33 "B.Fab" user "Ref Des/Assembly Bottom")
	)
	(footprint ""
		(layer "F.Cu")
		(at 261.747 -137.795 -90)
		(property "Reference" "H2"
			(at -6.213094 11.432794 0)
			(unlocked yes)
			(layer "F.SilkS")
			(effects
				(font
					(size 0.7874 0.5842)
					(thickness 0.1524)
				)
				(justify left)
			)
		)
		(property "Value" ""
			(at 0 0 270)
			(layer "F.Fab")
			(effects
				(font
					(size 1.27 1.27)
				)
			)
		)
		(duplicate_pad_numbers_are_jumpers no)
		(pad "1" thru_hole oval
			(at 0 0 270)
			(size 10.0076 32.004)
			(drill 3.0226
				(offset 0 10.999978)
			)
			(layers "*.Cu" "*.Mask")
			(remove_unused_layers no)
			(net "GND")
			(clearance -1.995678)
			(padstack
				(mode front_inner_back)
				(layer "Inner"
					(shape circle)
					(size 0 0)
					(clearance 0)
				)
				(layer "B.Cu"
					(shape oval)
					(size 10.0076 32.004)
					(offset 0 10.999978)
					(clearance -1.995678)
				)
			)
		)
	)
	(footprint ""
		(layer "F.Cu")
		(at 301.625 -122.9995)
		(property "Reference" "PR6956"
			(at 0 0 0)
			(layer "F.SilkS")
			(hide yes)
			(effects
				(font
					(size 1.27 1.27)
				)
			)
		)
		(property "Value" ""
			(at 0 0 0)
			(layer "F.Fab")
			(effects
				(font
					(size 1.27 1.27)
				)
			)
		)
		(duplicate_pad_numbers_are_jumpers no)
		(fp_line
			(start -1.2954 -0.5842)
			(end 1.2954 -0.5842)
			(stroke
				(width 0.1524)
				(type default)
			)
			(layer "F.SilkS")
		)
		(fp_line
			(start -1.2954 0.5842)
			(end -1.2954 -0.5842)
			(stroke
				(width 0.1524)
				(type default)
			)
			(layer "F.SilkS")
		)
		(fp_line
			(start 1.2954 -0.5842)
			(end 1.2954 0.5842)
			(stroke
				(width 0.1524)
				(type default)
			)
			(layer "F.SilkS")
		)
		(fp_line
			(start 1.2954 0.5842)
			(end -1.2954 0.5842)
			(stroke
				(width 0.1524)
				(type default)
			)
			(layer "F.SilkS")
		)
		(fp_line
			(start -1.1938 -0.406654)
			(end -0.8636 -0.406654)
			(stroke
				(width 0.1)
				(type default)
			)
			(layer "F.Fab")
		)
		(fp_line
			(start -1.1938 0.4064)
			(end -1.1938 -0.406654)
			(stroke
				(width 0.1)
				(type default)
			)
			(layer "F.Fab")
		)
		(fp_line
			(start -0.8636 -0.4572)
			(end 0.8636 -0.4572)
			(stroke
				(width 0.1)
				(type default)
			)
			(layer "F.Fab")
		)
		(fp_line
			(start -0.8636 -0.406654)
			(end -0.8636 -0.4572)
			(stroke
				(width 0.1)
				(type default)
			)
			(layer "F.Fab")
		)
		(fp_line
			(start -0.8636 0.4064)
			(end -1.1938 0.4064)
			(stroke
				(width 0.1)
				(type default)
			)
			(layer "F.Fab")
		)
		(fp_line
			(start -0.8636 0.4318)
			(end -0.8636 0.4064)
			(stroke
				(width 0.1)
				(type default)
			)
			(layer "F.Fab")
		)
		(fp_line
			(start -0.8636 0.4572)
			(end -0.8636 0.4318)
			(stroke
				(width 0.1)
				(type default)
			)
			(layer "F.Fab")
		)
		(fp_line
			(start 0.8636 -0.4572)
			(end 0.8636 -0.406654)
			(stroke
				(width 0.1)
				(type default)
			)
			(layer "F.Fab")
		)
		(fp_line
			(start 0.8636 -0.406654)
			(end 1.1938 -0.406654)
			(stroke
				(width 0.1)
				(type default)
			)
			(layer "F.Fab")
		)
		(fp_line
			(start 0.8636 0.4064)
			(end 0.8636 0.4572)
			(stroke
				(width 0.1)
				(type default)
			)
			(layer "F.Fab")
		)
		(fp_line
			(start 0.8636 0.4572)
			(end -0.8636 0.4572)
			(stroke
				(width 0.1)
				(type default)
			)
			(layer "F.Fab")
		)
		(fp_line
			(start 1.1938 -0.406654)
			(end 1.1938 0.4064)
			(stroke
				(width 0.1)
				(type default)
			)
			(layer "F.Fab")
		)
		(fp_line
			(start 1.1938 0.4064)
			(end 0.8636 0.4064)
			(stroke
				(width 0.1)
				(type default)
			)
			(layer "F.Fab")
		)
		(pad "1" smd rect
			(at -0.7366 0 270)
			(size 0.7112 0.8128)
			(layers "F.Cu" "F.Mask" "F.Paste")
			(net "P52V_HS_4287_S1P")
		)
		(pad "2" smd rect
			(at 0.7366 0 270)
			(size 0.7112 0.8128)
			(layers "F.Cu" "F.Mask" "F.Paste")
			(net "P52V_HS1_SENSE_P_R1")
		)
	)
	(footprint ""
		(layer "F.Cu")
		(at 66.430906 -136.906 90)
		(property "Reference" "PC71"
			(at 6.19633 1.133094 0)
			(unlocked yes)
			(layer "F.SilkS")
			(effects
				(font
					(size 0.7874 0.5842)
					(thickness 0.1524)
				)
				(justify left)
			)
		)
		(property "Value" ""
			(at 0 0 90)
			(layer "F.Fab")
			(effects
				(font
					(size 1.27 1.27)
				)
			)
		)
		(duplicate_pad_numbers_are_jumpers no)
		(fp_line
			(start 5.2578 2.499868)
			(end -5.2578 2.499868)
			(stroke
				(width 0.1524)
				(type default)
			)
			(layer "F.SilkS")
		)
		(fp_circle
			(center 0 2.500122)
			(end 0 7.758176)
			(stroke
				(width 0.1524)
				(type default)
			)
			(fill no)
			(layer "F.SilkS")
		)
		(fp_poly
			(pts
				(arc
					(start 5.2578 2.499868)
					(mid 0 7.757922)
					(end -5.2578 2.499868)
				)
			)
			(stroke
				(width 0)
				(type default)
			)
			(fill yes)
			(layer "F.SilkS")
		)
		(fp_circle
			(center 0 2.500122)
			(end 0 7.758176)
			(stroke
				(width 0.1)
				(type default)
			)
			(fill no)
			(layer "F.Fab")
		)
		(pad "1" thru_hole rect
			(at 0 0)
			(size 1.5748 1.5748)
			(drill 1.0668)
			(layers "*.Cu" "*.Mask")
			(remove_unused_layers no)
			(net "P52V_HS_FILTER")
			(clearance 0)
			(padstack
				(mode front_inner_back)
				(layer "Inner"
					(shape circle)
					(size 1.5748 1.5748)
					(clearance 0)
				)
				(layer "B.Cu"
					(shape rect)
					(size 1.5748 1.5748)
					(clearance 0)
				)
			)
		)
		(pad "2" thru_hole circle
			(at 0 4.99999)
			(size 1.5748 1.5748)
			(drill 1.0668)
			(layers "*.Cu" "*.Mask")
			(remove_unused_layers no)
			(net "GND")
			(clearance 0)
		)
	)
	(footprint ""
		(layer "F.Cu")
		(at 289.722814 -50.698146 90)
		(property "Reference" "PC558"
			(at 0 0 90)
			(layer "F.SilkS")
			(hide yes)
			(effects
				(font
					(size 1.27 1.27)
				)
			)
		)
		(property "Value" ""
			(at 0 0 90)
			(layer "F.Fab")
			(effects
				(font
					(size 1.27 1.27)
				)
			)
		)
		(duplicate_pad_numbers_are_jumpers no)
		(fp_line
			(start 2.2098 -0.9398)
			(end 2.2098 0.9398)
			(stroke
				(width 0.1524)
				(type default)
			)
			(layer "F.SilkS")
		)
		(fp_line
			(start -2.2098 -0.9398)
			(end 2.2098 -0.9398)
			(stroke
				(width 0.1524)
				(type default)
			)
			(layer "F.SilkS")
		)
		(fp_line
			(start 2.2098 0.9398)
			(end -2.2098 0.9398)
			(stroke
				(width 0.1524)
				(type default)
			)
			(layer "F.SilkS")
		)
		(fp_line
			(start -2.2098 0.9398)
			(end -2.2098 -0.9398)
			(stroke
				(width 0.1524)
				(type default)
			)
			(layer "F.SilkS")
		)
		(fp_line
			(start 1.6764 -0.9398)
			(end -1.6764 -0.9398)
			(stroke
				(width 0.1)
				(type default)
			)
			(layer "F.Fab")
		)
		(fp_line
			(start -1.6764 -0.9398)
			(end -1.6764 0.9398)
			(stroke
				(width 0.1)
				(type default)
			)
			(layer "F.Fab")
		)
		(fp_line
			(start 1.6764 0.9398)
			(end 1.6764 -0.9398)
			(stroke
				(width 0.1)
				(type default)
			)
			(layer "F.Fab")
		)
		(fp_line
			(start -1.6764 0.9398)
			(end 1.6764 0.9398)
			(stroke
				(width 0.1)
				(type default)
			)
			(layer "F.Fab")
		)
		(pad "1" smd rect
			(at -1.4732 0 270)
			(size 1.1684 1.5748)
			(layers "F.Cu" "F.Mask" "F.Paste")
			(net "P52V_HS1_VCC")
		)
		(pad "2" smd rect
			(at 1.4732 0 270)
			(size 1.1684 1.5748)
			(layers "F.Cu" "F.Mask" "F.Paste")
			(net "GND_FIELD_SIGNAL")
		)
	)
	(footprint ""
		(layer "F.Cu")
		(at 163.6268 -11.4808)
		(property "Reference" "PL1"
			(at 0 0 0)
			(layer "F.SilkS")
			(hide yes)
			(effects
				(font
					(size 1.27 1.27)
				)
			)
		)
		(property "Value" ""
			(at 0 0 0)
			(layer "F.Fab")
			(effects
				(font
					(size 1.27 1.27)
				)
			)
		)
		(duplicate_pad_numbers_are_jumpers no)
		(fp_line
			(start -1.27 -0.5842)
			(end 1.27 -0.5842)
			(stroke
				(width 0.1524)
				(type default)
			)
			(layer "F.SilkS")
		)
		(fp_line
			(start -1.27 -0.5588)
			(end -1.27 -0.5842)
			(stroke
				(width 0.1524)
				(type default)
			)
			(layer "F.SilkS")
		)
		(fp_line
			(start -1.27 0.5842)
			(end -1.27 -0.5842)
			(stroke
				(width 0.1524)
				(type default)
			)
			(layer "F.SilkS")
		)
		(fp_line
			(start 1.27 0.5842)
			(end -1.27 0.5842)
			(stroke
				(width 0.1524)
				(type default)
			)
			(layer "F.SilkS")
		)
		(fp_line
			(start 1.27 0.5842)
			(end 1.27 -0.5842)
			(stroke
				(width 0.1524)
				(type default)
			)
			(layer "F.SilkS")
		)
		(fp_line
			(start -1.194308 -0.406654)
			(end -0.9144 -0.406654)
			(stroke
				(width 0.1)
				(type default)
			)
			(layer "F.Fab")
		)
		(fp_line
			(start -1.194308 0.406654)
			(end -1.194308 -0.406654)
			(stroke
				(width 0.1)
				(type default)
			)
			(layer "F.Fab")
		)
		(fp_line
			(start -0.9144 -0.508)
			(end 0.9144 -0.508)
			(stroke
				(width 0.1)
				(type default)
			)
			(layer "F.Fab")
		)
		(fp_line
			(start -0.9144 -0.406654)
			(end -0.9144 -0.508)
			(stroke
				(width 0.1)
				(type default)
			)
			(layer "F.Fab")
		)
		(fp_line
			(start -0.9144 0.406654)
			(end -1.194308 0.406654)
			(stroke
				(width 0.1)
				(type default)
			)
			(layer "F.Fab")
		)
		(fp_line
			(start -0.9144 0.508)
			(end -0.9144 0.406654)
			(stroke
				(width 0.1)
				(type default)
			)
			(layer "F.Fab")
		)
		(fp_line
			(start 0.9144 -0.508)
			(end 0.9144 -0.406654)
			(stroke
				(width 0.1)
				(type default)
			)
			(layer "F.Fab")
		)
		(fp_line
			(start 0.9144 -0.406654)
			(end 1.1938 -0.406654)
			(stroke
				(width 0.1)
				(type default)
			)
			(layer "F.Fab")
		)
		(fp_line
			(start 0.9144 0.4064)
			(end 0.9144 0.508)
			(stroke
				(width 0.1)
				(type default)
			)
			(layer "F.Fab")
		)
		(fp_line
			(start 0.9144 0.508)
			(end -0.9144 0.508)
			(stroke
				(width 0.1)
				(type default)
			)
			(layer "F.Fab")
		)
		(fp_line
			(start 1.1938 -0.406654)
			(end 1.1938 0.4064)
			(stroke
				(width 0.1)
				(type default)
			)
			(layer "F.Fab")
		)
		(fp_line
			(start 1.1938 0.4064)
			(end 0.9144 0.4064)
			(stroke
				(width 0.1)
				(type default)
			)
			(layer "F.Fab")
		)
		(pad "1" smd rect
			(at -0.7366 0 270)
			(size 0.7112 0.8128)
			(layers "F.Cu" "F.Mask" "F.Paste")
			(net "P12V_BRICK")
		)
		(pad "2" smd rect
			(at 0.7366 0 270)
			(size 0.7112 0.8128)
			(layers "F.Cu" "F.Mask" "F.Paste")
			(net "SW_P12V_FILT__P3V3_AUX")
		)
	)
	(footprint ""
		(layer "F.Cu")
		(at 151.765 -51.816)
		(property "Reference" "PC38"
			(at 0 0 0)
			(layer "F.SilkS")
			(hide yes)
			(effects
				(font
					(size 1.27 1.27)
				)
			)
		)
		(property "Value" ""
			(at 0 0 0)
			(layer "F.Fab")
			(effects
				(font
					(size 1.27 1.27)
				)
			)
		)
		(duplicate_pad_numbers_are_jumpers no)
		(fp_line
			(start -1.524 -0.762)
			(end 1.524 -0.762)
			(stroke
				(width 0.1524)
				(type default)
			)
			(layer "F.SilkS")
		)
		(fp_line
			(start -1.524 0.762)
			(end -1.524 -0.762)
			(stroke
				(width 0.1524)
				(type default)
			)
			(layer "F.SilkS")
		)
		(fp_line
			(start 1.524 -0.762)
			(end 1.524 0.762)
			(stroke
				(width 0.1524)
				(type default)
			)
			(layer "F.SilkS")
		)
		(fp_line
			(start 1.524 0.762)
			(end -1.524 0.762)
			(stroke
				(width 0.1524)
				(type default)
			)
			(layer "F.SilkS")
		)
		(fp_line
			(start -1.1049 -0.724916)
			(end -1.1049 0.724916)
			(stroke
				(width 0.1)
				(type default)
			)
			(layer "F.Fab")
		)
		(fp_line
			(start -1.1049 0.724916)
			(end 1.1049 0.724916)
			(stroke
				(width 0.1)
				(type default)
			)
			(layer "F.Fab")
		)
		(fp_line
			(start 1.1049 -0.724916)
			(end -1.1049 -0.724916)
			(stroke
				(width 0.1)
				(type default)
			)
			(layer "F.Fab")
		)
		(fp_line
			(start 1.1049 0.724916)
			(end 1.1049 -0.724916)
			(stroke
				(width 0.1)
				(type default)
			)
			(layer "F.Fab")
		)
		(pad "1" smd rect
			(at -0.889 0 180)
			(size 1.016 1.27)
			(layers "F.Cu" "F.Mask" "F.Paste")
			(net "P12V_BRICK")
		)
		(pad "2" smd rect
			(at 0.889 0 180)
			(size 1.016 1.27)
			(layers "F.Cu" "F.Mask" "F.Paste")
			(net "GND")
		)
	)
	(footprint ""
		(layer "F.Cu")
		(at 284.988 -49.276 90)
		(property "Reference" "PC557"
			(at 0 0 90)
			(layer "F.SilkS")
			(hide yes)
			(effects
				(font
					(size 1.27 1.27)
				)
			)
		)
		(property "Value" ""
			(at 0 0 90)
			(layer "F.Fab")
			(effects
				(font
					(size 1.27 1.27)
				)
			)
		)
		(duplicate_pad_numbers_are_jumpers no)
		(fp_line
			(start 0.7874 -0.4064)
			(end 0.7874 0.4064)
			(stroke
				(width 0.1524)
				(type default)
			)
			(layer "F.SilkS")
		)
		(fp_line
			(start -0.7874 -0.4064)
			(end 0.7874 -0.4064)
			(stroke
				(width 0.1524)
				(type default)
			)
			(layer "F.SilkS")
		)
		(fp_line
			(start 0.7874 0.4064)
			(end -0.7874 0.4064)
			(stroke
				(width 0.1524)
				(type default)
			)
			(layer "F.SilkS")
		)
		(fp_line
			(start -0.7874 0.4064)
			(end -0.7874 -0.4064)
			(stroke
				(width 0.1524)
				(type default)
			)
			(layer "F.SilkS")
		)
		(fp_line
			(start -0.12065 -0.305054)
			(end -0.12065 -0.2794)
			(stroke
				(width 0.1)
				(type default)
			)
			(layer "F.Fab")
		)
		(fp_line
			(start -0.67945 -0.305054)
			(end -0.12065 -0.305054)
			(stroke
				(width 0.1)
				(type default)
			)
			(layer "F.Fab")
		)
		(fp_line
			(start 0.67945 -0.3048)
			(end 0.67945 0.3048)
			(stroke
				(width 0.1)
				(type default)
			)
			(layer "F.Fab")
		)
		(fp_line
			(start 0.12065 -0.3048)
			(end 0.67945 -0.3048)
			(stroke
				(width 0.1)
				(type default)
			)
			(layer "F.Fab")
		)
		(fp_line
			(start 0.12065 -0.2794)
			(end 0.12065 -0.3048)
			(stroke
				(width 0.1)
				(type default)
			)
			(layer "F.Fab")
		)
		(fp_line
			(start -0.12065 -0.2794)
			(end 0.12065 -0.2794)
			(stroke
				(width 0.1)
				(type default)
			)
			(layer "F.Fab")
		)
		(fp_line
			(start 0.120396 0.2794)
			(end -0.12065 0.2794)
			(stroke
				(width 0.1)
				(type default)
			)
			(layer "F.Fab")
		)
		(fp_line
			(start -0.12065 0.2794)
			(end -0.12065 0.3048)
			(stroke
				(width 0.1)
				(type default)
			)
			(layer "F.Fab")
		)
		(fp_line
			(start 0.67945 0.3048)
			(end 0.120396 0.3048)
			(stroke
				(width 0.1)
				(type default)
			)
			(layer "F.Fab")
		)
		(fp_line
			(start 0.120396 0.3048)
			(end 0.120396 0.2794)
			(stroke
				(width 0.1)
				(type default)
			)
			(layer "F.Fab")
		)
		(fp_line
			(start -0.12065 0.3048)
			(end -0.67945 0.3048)
			(stroke
				(width 0.1)
				(type default)
			)
			(layer "F.Fab")
		)
		(fp_line
			(start -0.67945 0.3048)
			(end -0.67945 -0.305054)
			(stroke
				(width 0.1)
				(type default)
			)
			(layer "F.Fab")
		)
		(pad "1" smd circle
			(at -0.40005 0 90)
			(size 0 0)
			(layers "F.Cu" "F.Mask" "F.Paste")
			(net "P52V_HS1_UVH")
		)
		(pad "2" smd circle
			(at 0.40005 0 90)
			(size 0 0)
			(layers "F.Cu" "F.Mask" "F.Paste")
			(net "GND_FIELD_SIGNAL")
		)
	)
	(footprint ""
		(layer "F.Cu")
		(at 173.609 -51.816)
		(property "Reference" "PC30"
			(at 0 0 0)
			(layer "F.SilkS")
			(hide yes)
			(effects
				(font
					(size 1.27 1.27)
				)
			)
		)
		(property "Value" ""
			(at 0 0 0)
			(layer "F.Fab")
			(effects
				(font
					(size 1.27 1.27)
				)
			)
		)
		(duplicate_pad_numbers_are_jumpers no)
		(fp_line
			(start -1.524 -0.762)
			(end 1.524 -0.762)
			(stroke
				(width 0.1524)
				(type default)
			)
			(layer "F.SilkS")
		)
		(fp_line
			(start -1.524 0.762)
			(end -1.524 -0.762)
			(stroke
				(width 0.1524)
				(type default)
			)
			(layer "F.SilkS")
		)
		(fp_line
			(start 1.524 -0.762)
			(end 1.524 0.762)
			(stroke
				(width 0.1524)
				(type default)
			)
			(layer "F.SilkS")
		)
		(fp_line
			(start 1.524 0.762)
			(end -1.524 0.762)
			(stroke
				(width 0.1524)
				(type default)
			)
			(layer "F.SilkS")
		)
		(fp_line
			(start -1.1049 -0.724916)
			(end -1.1049 0.724916)
			(stroke
				(width 0.1)
				(type default)
			)
			(layer "F.Fab")
		)
		(fp_line
			(start -1.1049 0.724916)
			(end 1.1049 0.724916)
			(stroke
				(width 0.1)
				(type default)
			)
			(layer "F.Fab")
		)
		(fp_line
			(start 1.1049 -0.724916)
			(end -1.1049 -0.724916)
			(stroke
				(width 0.1)
				(type default)
			)
			(layer "F.Fab")
		)
		(fp_line
			(start 1.1049 0.724916)
			(end 1.1049 -0.724916)
			(stroke
				(width 0.1)
				(type default)
			)
			(layer "F.Fab")
		)
		(pad "1" smd rect
			(at -0.889 0 180)
			(size 1.016 1.27)
			(layers "F.Cu" "F.Mask" "F.Paste")
			(net "P12V_BRICK")
		)
		(pad "2" smd rect
			(at 0.889 0 180)
			(size 1.016 1.27)
			(layers "F.Cu" "F.Mask" "F.Paste")
			(net "GND")
		)
	)
)
